(kicad_pcb
	(version 20260206)
	(generator "pcbnew")
	(generator_version "10.0")
	(general
		(thickness 1.6)
		(legacy_teardrops no)
	)
	(paper "A4")
	(title_block
		(title "03242023_DA0F0TMBIJ0_F0T_Motherboard_J_brd_V01_OCP.brd")
		(comment 1 "Grand Teton / footprints 4553-4558 of 6105")
	)
	(layers
		(0 "F.Cu" signal "TOP")
		(4 "In1.Cu" signal "GND")
		(6 "In2.Cu" signal "IN1")
		(8 "In3.Cu" signal "GND1")
		(10 "In4.Cu" signal "IN2")
		(12 "In5.Cu" signal "GND2")
		(14 "In6.Cu" signal "IN3")
		(16 "In7.Cu" signal "GND3")
		(18 "In8.Cu" signal "VCC")
		(20 "In9.Cu" signal "VCC1")
		(22 "In10.Cu" signal "GND4")
		(24 "In11.Cu" signal "IN4")
		(26 "In12.Cu" signal "GND5")
		(28 "In13.Cu" signal "IN5")
		(30 "In14.Cu" signal "GND6")
		(32 "In15.Cu" signal "IN6")
		(34 "In16.Cu" signal "GND7")
		(2 "B.Cu" signal "BOTTOM")
		(9 "F.Adhes" user "F.Adhesive")
		(11 "B.Adhes" user "B.Adhesive")
		(13 "F.Paste" user "Package Geometry/Pastemask Top")
		(15 "B.Paste" user "Package Geometry/Pastemask Bottom")
		(5 "F.SilkS" user "Ref Des/Silkscreen Top")
		(7 "B.SilkS" user "Ref Des/Silkscreen Bottom")
		(1 "F.Mask" user "Board Geometry/Soldermask Top")
		(3 "B.Mask" user "Board Geometry/Soldermask Bottom")
		(17 "Dwgs.User" user "User.Drawings")
		(19 "Cmts.User" user "User.Comments")
		(21 "Eco1.User" user "User.Eco1")
		(23 "Eco2.User" user "User.Eco2")
		(25 "Edge.Cuts" user "Board Geometry/Outline")
		(27 "Margin" user)
		(31 "F.CrtYd" user "Package Geometry/Place Bound Top")
		(29 "B.CrtYd" user "Package Geometry/Place Bound Bottom")
		(35 "F.Fab" user "Ref Des/Assembly Top")
		(33 "B.Fab" user "Ref Des/Assembly Bottom")
	)
	(footprint ""
		(layer "B.Cu")
		(at 430.8221 -51.42738 180)
		(property "Reference" "C2359"
			(at 0 0 0)
			(layer "B.SilkS")
			(hide yes)
			(effects
				(font
					(size 1.27 1.27)
				)
				(justify mirror)
			)
		)
		(property "Value" ""
			(at 0 0 0)
			(layer "B.Fab")
			(effects
				(font
					(size 1.27 1.27)
				)
				(justify mirror)
			)
		)
		(duplicate_pad_numbers_are_jumpers no)
		(fp_line
			(start 0.7874 0.4064)
			(end 0.7874 -0.4064)
			(stroke
				(width 0.1524)
				(type default)
			)
			(layer "B.SilkS")
		)
		(fp_line
			(start 0.7874 -0.4064)
			(end -0.7874 -0.4064)
			(stroke
				(width 0.1524)
				(type default)
			)
			(layer "B.SilkS")
		)
		(fp_line
			(start -0.7874 0.4064)
			(end 0.7874 0.4064)
			(stroke
				(width 0.1524)
				(type default)
			)
			(layer "B.SilkS")
		)
		(fp_line
			(start -0.7874 -0.4064)
			(end -0.7874 0.4064)
			(stroke
				(width 0.1524)
				(type default)
			)
			(layer "B.SilkS")
		)
		(fp_line
			(start 0.67945 0.3048)
			(end 0.67945 -0.305054)
			(stroke
				(width 0.1)
				(type default)
			)
			(layer "B.Fab")
		)
		(fp_line
			(start 0.67945 -0.305054)
			(end 0.12065 -0.305054)
			(stroke
				(width 0.1)
				(type default)
			)
			(layer "B.Fab")
		)
		(fp_line
			(start 0.12065 0.3048)
			(end 0.67945 0.3048)
			(stroke
				(width 0.1)
				(type default)
			)
			(layer "B.Fab")
		)
		(fp_line
			(start 0.12065 0.2794)
			(end 0.12065 0.3048)
			(stroke
				(width 0.1)
				(type default)
			)
			(layer "B.Fab")
		)
		(fp_line
			(start 0.12065 -0.2794)
			(end -0.12065 -0.2794)
			(stroke
				(width 0.1)
				(type default)
			)
			(layer "B.Fab")
		)
		(fp_line
			(start 0.12065 -0.305054)
			(end 0.12065 -0.2794)
			(stroke
				(width 0.1)
				(type default)
			)
			(layer "B.Fab")
		)
		(fp_line
			(start -0.120396 0.3048)
			(end -0.120396 0.2794)
			(stroke
				(width 0.1)
				(type default)
			)
			(layer "B.Fab")
		)
		(fp_line
			(start -0.120396 0.2794)
			(end 0.12065 0.2794)
			(stroke
				(width 0.1)
				(type default)
			)
			(layer "B.Fab")
		)
		(fp_line
			(start -0.12065 -0.2794)
			(end -0.12065 -0.3048)
			(stroke
				(width 0.1)
				(type default)
			)
			(layer "B.Fab")
		)
		(fp_line
			(start -0.12065 -0.3048)
			(end -0.67945 -0.3048)
			(stroke
				(width 0.1)
				(type default)
			)
			(layer "B.Fab")
		)
		(fp_line
			(start -0.67945 0.3048)
			(end -0.120396 0.3048)
			(stroke
				(width 0.1)
				(type default)
			)
			(layer "B.Fab")
		)
		(fp_line
			(start -0.67945 -0.3048)
			(end -0.67945 0.3048)
			(stroke
				(width 0.1)
				(type default)
			)
			(layer "B.Fab")
		)
		(pad "1" smd circle
			(at 0.40005 0)
			(size 0 0)
			(layers "B.Cu" "B.Mask" "B.Paste")
			(net "PWRGD_P5V_ISO_R")
		)
		(pad "2" smd circle
			(at -0.40005 0)
			(size 0 0)
			(layers "B.Cu" "B.Mask" "B.Paste")
			(net "GND")
		)
	)
	(footprint ""
		(layer "B.Cu")
		(at 34.551366 -192.924176 -90)
		(property "Reference" "C614"
			(at 0 0 90)
			(layer "B.SilkS")
			(hide yes)
			(effects
				(font
					(size 1.27 1.27)
				)
				(justify mirror)
			)
		)
		(property "Value" ""
			(at 0 0 90)
			(layer "B.Fab")
			(effects
				(font
					(size 1.27 1.27)
				)
				(justify mirror)
			)
		)
		(duplicate_pad_numbers_are_jumpers no)
		(fp_line
			(start -0.7874 0.4064)
			(end 0.7874 0.4064)
			(stroke
				(width 0.1524)
				(type default)
			)
			(layer "B.SilkS")
		)
		(fp_line
			(start 0.7874 0.4064)
			(end 0.7874 -0.4064)
			(stroke
				(width 0.1524)
				(type default)
			)
			(layer "B.SilkS")
		)
		(fp_line
			(start -0.7874 -0.4064)
			(end -0.7874 0.4064)
			(stroke
				(width 0.1524)
				(type default)
			)
			(layer "B.SilkS")
		)
		(fp_line
			(start 0.7874 -0.4064)
			(end -0.7874 -0.4064)
			(stroke
				(width 0.1524)
				(type default)
			)
			(layer "B.SilkS")
		)
		(fp_line
			(start -0.67945 0.3048)
			(end -0.120396 0.3048)
			(stroke
				(width 0.1)
				(type default)
			)
			(layer "B.Fab")
		)
		(fp_line
			(start -0.120396 0.3048)
			(end -0.120396 0.2794)
			(stroke
				(width 0.1)
				(type default)
			)
			(layer "B.Fab")
		)
		(fp_line
			(start 0.12065 0.3048)
			(end 0.67945 0.3048)
			(stroke
				(width 0.1)
				(type default)
			)
			(layer "B.Fab")
		)
		(fp_line
			(start 0.67945 0.3048)
			(end 0.67945 -0.305054)
			(stroke
				(width 0.1)
				(type default)
			)
			(layer "B.Fab")
		)
		(fp_line
			(start -0.120396 0.2794)
			(end 0.12065 0.2794)
			(stroke
				(width 0.1)
				(type default)
			)
			(layer "B.Fab")
		)
		(fp_line
			(start 0.12065 0.2794)
			(end 0.12065 0.3048)
			(stroke
				(width 0.1)
				(type default)
			)
			(layer "B.Fab")
		)
		(fp_line
			(start -0.12065 -0.2794)
			(end -0.12065 -0.3048)
			(stroke
				(width 0.1)
				(type default)
			)
			(layer "B.Fab")
		)
		(fp_line
			(start 0.12065 -0.2794)
			(end -0.12065 -0.2794)
			(stroke
				(width 0.1)
				(type default)
			)
			(layer "B.Fab")
		)
		(fp_line
			(start -0.67945 -0.3048)
			(end -0.67945 0.3048)
			(stroke
				(width 0.1)
				(type default)
			)
			(layer "B.Fab")
		)
		(fp_line
			(start -0.12065 -0.3048)
			(end -0.67945 -0.3048)
			(stroke
				(width 0.1)
				(type default)
			)
			(layer "B.Fab")
		)
		(fp_line
			(start 0.12065 -0.305054)
			(end 0.12065 -0.2794)
			(stroke
				(width 0.1)
				(type default)
			)
			(layer "B.Fab")
		)
		(fp_line
			(start 0.67945 -0.305054)
			(end 0.12065 -0.305054)
			(stroke
				(width 0.1)
				(type default)
			)
			(layer "B.Fab")
		)
		(pad "1" smd circle
			(at 0.40005 0 90)
			(size 0 0)
			(layers "B.Cu" "B.Mask" "B.Paste")
			(net "RST_PLD_CPU1_DRAM_AB_N")
		)
		(pad "2" smd circle
			(at -0.40005 0 90)
			(size 0 0)
			(layers "B.Cu" "B.Mask" "B.Paste")
			(net "GND")
		)
	)
	(footprint ""
		(layer "B.Cu")
		(at 193.60388 -107.495848 180)
		(property "Reference" "R1437"
			(at 0 0 0)
			(layer "B.SilkS")
			(hide yes)
			(effects
				(font
					(size 1.27 1.27)
				)
				(justify mirror)
			)
		)
		(property "Value" ""
			(at 0 0 0)
			(layer "B.Fab")
			(effects
				(font
					(size 1.27 1.27)
				)
				(justify mirror)
			)
		)
		(duplicate_pad_numbers_are_jumpers no)
		(fp_line
			(start 0.7874 0.4064)
			(end 0.7874 -0.4064)
			(stroke
				(width 0.1524)
				(type default)
			)
			(layer "B.SilkS")
		)
		(fp_line
			(start 0.7874 -0.4064)
			(end -0.7874 -0.4064)
			(stroke
				(width 0.1524)
				(type default)
			)
			(layer "B.SilkS")
		)
		(fp_line
			(start -0.7874 0.4064)
			(end 0.7874 0.4064)
			(stroke
				(width 0.1524)
				(type default)
			)
			(layer "B.SilkS")
		)
		(fp_line
			(start -0.7874 -0.4064)
			(end -0.7874 0.4064)
			(stroke
				(width 0.1524)
				(type default)
			)
			(layer "B.SilkS")
		)
		(fp_line
			(start 0.67945 0.3048)
			(end 0.67945 -0.305054)
			(stroke
				(width 0.1)
				(type default)
			)
			(layer "B.Fab")
		)
		(fp_line
			(start 0.67945 -0.305054)
			(end 0.12065 -0.305054)
			(stroke
				(width 0.1)
				(type default)
			)
			(layer "B.Fab")
		)
		(fp_line
			(start 0.12065 0.3048)
			(end 0.67945 0.3048)
			(stroke
				(width 0.1)
				(type default)
			)
			(layer "B.Fab")
		)
		(fp_line
			(start 0.12065 0.2794)
			(end 0.12065 0.3048)
			(stroke
				(width 0.1)
				(type default)
			)
			(layer "B.Fab")
		)
		(fp_line
			(start 0.12065 -0.2794)
			(end -0.12065 -0.2794)
			(stroke
				(width 0.1)
				(type default)
			)
			(layer "B.Fab")
		)
		(fp_line
			(start 0.12065 -0.305054)
			(end 0.12065 -0.2794)
			(stroke
				(width 0.1)
				(type default)
			)
			(layer "B.Fab")
		)
		(fp_line
			(start -0.120396 0.3048)
			(end -0.120396 0.2794)
			(stroke
				(width 0.1)
				(type default)
			)
			(layer "B.Fab")
		)
		(fp_line
			(start -0.120396 0.2794)
			(end 0.12065 0.2794)
			(stroke
				(width 0.1)
				(type default)
			)
			(layer "B.Fab")
		)
		(fp_line
			(start -0.12065 -0.2794)
			(end -0.12065 -0.3048)
			(stroke
				(width 0.1)
				(type default)
			)
			(layer "B.Fab")
		)
		(fp_line
			(start -0.12065 -0.3048)
			(end -0.67945 -0.3048)
			(stroke
				(width 0.1)
				(type default)
			)
			(layer "B.Fab")
		)
		(fp_line
			(start -0.67945 0.3048)
			(end -0.120396 0.3048)
			(stroke
				(width 0.1)
				(type default)
			)
			(layer "B.Fab")
		)
		(fp_line
			(start -0.67945 -0.3048)
			(end -0.67945 0.3048)
			(stroke
				(width 0.1)
				(type default)
			)
			(layer "B.Fab")
		)
		(pad "1" smd circle
			(at 0.40005 0)
			(size 0 0)
			(layers "B.Cu" "B.Mask" "B.Paste")
			(net "FM_PLD_HEARTBEAT_LVC3")
		)
		(pad "2" smd circle
			(at -0.40005 0)
			(size 0 0)
			(layers "B.Cu" "B.Mask" "B.Paste")
			(net "P3V3_AUX")
		)
	)
	(footprint ""
		(layer "B.Cu")
		(at 69.404484 -190.795656 90)
		(property "Reference" "R558"
			(at 0 0 90)
			(layer "B.SilkS")
			(hide yes)
			(effects
				(font
					(size 1.27 1.27)
				)
				(justify mirror)
			)
		)
		(property "Value" ""
			(at 0 0 90)
			(layer "B.Fab")
			(effects
				(font
					(size 1.27 1.27)
				)
				(justify mirror)
			)
		)
		(duplicate_pad_numbers_are_jumpers no)
		(fp_line
			(start 0.7874 -0.4064)
			(end -0.7874 -0.4064)
			(stroke
				(width 0.1524)
				(type default)
			)
			(layer "B.SilkS")
		)
		(fp_line
			(start -0.7874 -0.4064)
			(end -0.7874 0.4064)
			(stroke
				(width 0.1524)
				(type default)
			)
			(layer "B.SilkS")
		)
		(fp_line
			(start 0.7874 0.4064)
			(end 0.7874 -0.4064)
			(stroke
				(width 0.1524)
				(type default)
			)
			(layer "B.SilkS")
		)
		(fp_line
			(start -0.7874 0.4064)
			(end 0.7874 0.4064)
			(stroke
				(width 0.1524)
				(type default)
			)
			(layer "B.SilkS")
		)
		(fp_line
			(start 0.67945 -0.305054)
			(end 0.12065 -0.305054)
			(stroke
				(width 0.1)
				(type default)
			)
			(layer "B.Fab")
		)
		(fp_line
			(start 0.12065 -0.305054)
			(end 0.12065 -0.2794)
			(stroke
				(width 0.1)
				(type default)
			)
			(layer "B.Fab")
		)
		(fp_line
			(start -0.12065 -0.3048)
			(end -0.67945 -0.3048)
			(stroke
				(width 0.1)
				(type default)
			)
			(layer "B.Fab")
		)
		(fp_line
			(start -0.67945 -0.3048)
			(end -0.67945 0.3048)
			(stroke
				(width 0.1)
				(type default)
			)
			(layer "B.Fab")
		)
		(fp_line
			(start 0.12065 -0.2794)
			(end -0.12065 -0.2794)
			(stroke
				(width 0.1)
				(type default)
			)
			(layer "B.Fab")
		)
		(fp_line
			(start -0.12065 -0.2794)
			(end -0.12065 -0.3048)
			(stroke
				(width 0.1)
				(type default)
			)
			(layer "B.Fab")
		)
		(fp_line
			(start 0.12065 0.2794)
			(end 0.12065 0.3048)
			(stroke
				(width 0.1)
				(type default)
			)
			(layer "B.Fab")
		)
		(fp_line
			(start -0.120396 0.2794)
			(end 0.12065 0.2794)
			(stroke
				(width 0.1)
				(type default)
			)
			(layer "B.Fab")
		)
		(fp_line
			(start 0.67945 0.3048)
			(end 0.67945 -0.305054)
			(stroke
				(width 0.1)
				(type default)
			)
			(layer "B.Fab")
		)
		(fp_line
			(start 0.12065 0.3048)
			(end 0.67945 0.3048)
			(stroke
				(width 0.1)
				(type default)
			)
			(layer "B.Fab")
		)
		(fp_line
			(start -0.120396 0.3048)
			(end -0.120396 0.2794)
			(stroke
				(width 0.1)
				(type default)
			)
			(layer "B.Fab")
		)
		(fp_line
			(start -0.67945 0.3048)
			(end -0.120396 0.3048)
			(stroke
				(width 0.1)
				(type default)
			)
			(layer "B.Fab")
		)
		(pad "1" smd circle
			(at 0.40005 0 270)
			(size 0 0)
			(layers "B.Cu" "B.Mask" "B.Paste")
			(net "SVID_ALERT0_CPU1_R_N")
		)
		(pad "2" smd circle
			(at -0.40005 0 270)
			(size 0 0)
			(layers "B.Cu" "B.Mask" "B.Paste")
			(net "PVNN_TERM_CPU1")
		)
	)
	(footprint ""
		(layer "B.Cu")
		(at 178.10988 -103.723948)
		(property "Reference" "C1935"
			(at 0 0 0)
			(layer "B.SilkS")
			(hide yes)
			(effects
				(font
					(size 1.27 1.27)
				)
				(justify mirror)
			)
		)
		(property "Value" ""
			(at 0 0 0)
			(layer "B.Fab")
			(effects
				(font
					(size 1.27 1.27)
				)
				(justify mirror)
			)
		)
		(duplicate_pad_numbers_are_jumpers no)
		(fp_line
			(start -0.7874 -0.4064)
			(end -0.7874 0.4064)
			(stroke
				(width 0.1524)
				(type default)
			)
			(layer "B.SilkS")
		)
		(fp_line
			(start -0.7874 0.4064)
			(end 0.7874 0.4064)
			(stroke
				(width 0.1524)
				(type default)
			)
			(layer "B.SilkS")
		)
		(fp_line
			(start 0.7874 -0.4064)
			(end -0.7874 -0.4064)
			(stroke
				(width 0.1524)
				(type default)
			)
			(layer "B.SilkS")
		)
		(fp_line
			(start 0.7874 0.4064)
			(end 0.7874 -0.4064)
			(stroke
				(width 0.1524)
				(type default)
			)
			(layer "B.SilkS")
		)
		(fp_line
			(start -0.67945 -0.3048)
			(end -0.67945 0.3048)
			(stroke
				(width 0.1)
				(type default)
			)
			(layer "B.Fab")
		)
		(fp_line
			(start -0.67945 0.3048)
			(end -0.120396 0.3048)
			(stroke
				(width 0.1)
				(type default)
			)
			(layer "B.Fab")
		)
		(fp_line
			(start -0.12065 -0.3048)
			(end -0.67945 -0.3048)
			(stroke
				(width 0.1)
				(type default)
			)
			(layer "B.Fab")
		)
		(fp_line
			(start -0.12065 -0.2794)
			(end -0.12065 -0.3048)
			(stroke
				(width 0.1)
				(type default)
			)
			(layer "B.Fab")
		)
		(fp_line
			(start -0.120396 0.2794)
			(end 0.12065 0.2794)
			(stroke
				(width 0.1)
				(type default)
			)
			(layer "B.Fab")
		)
		(fp_line
			(start -0.120396 0.3048)
			(end -0.120396 0.2794)
			(stroke
				(width 0.1)
				(type default)
			)
			(layer "B.Fab")
		)
		(fp_line
			(start 0.12065 -0.305054)
			(end 0.12065 -0.2794)
			(stroke
				(width 0.1)
				(type default)
			)
			(layer "B.Fab")
		)
		(fp_line
			(start 0.12065 -0.2794)
			(end -0.12065 -0.2794)
			(stroke
				(width 0.1)
				(type default)
			)
			(layer "B.Fab")
		)
		(fp_line
			(start 0.12065 0.2794)
			(end 0.12065 0.3048)
			(stroke
				(width 0.1)
				(type default)
			)
			(layer "B.Fab")
		)
		(fp_line
			(start 0.12065 0.3048)
			(end 0.67945 0.3048)
			(stroke
				(width 0.1)
				(type default)
			)
			(layer "B.Fab")
		)
		(fp_line
			(start 0.67945 -0.305054)
			(end 0.12065 -0.305054)
			(stroke
				(width 0.1)
				(type default)
			)
			(layer "B.Fab")
		)
		(fp_line
			(start 0.67945 0.3048)
			(end 0.67945 -0.305054)
			(stroke
				(width 0.1)
				(type default)
			)
			(layer "B.Fab")
		)
		(pad "1" smd circle
			(at 0.40005 0 180)
			(size 0 0)
			(layers "B.Cu" "B.Mask" "B.Paste")
			(net "P3V3_AUX_FPGA_VCCIO4")
		)
		(pad "2" smd circle
			(at -0.40005 0 180)
			(size 0 0)
			(layers "B.Cu" "B.Mask" "B.Paste")
			(net "GND")
		)
	)
	(footprint ""
		(layer "B.Cu")
		(at 261.73557 -317.881762 180)
		(property "Reference" "R3882"
			(at 0 0 0)
			(layer "B.SilkS")
			(hide yes)
			(effects
				(font
					(size 1.27 1.27)
				)
				(justify mirror)
			)
		)
		(property "Value" ""
			(at 0 0 0)
			(layer "B.Fab")
			(effects
				(font
					(size 1.27 1.27)
				)
				(justify mirror)
			)
		)
		(duplicate_pad_numbers_are_jumpers no)
		(fp_line
			(start 0.7874 0.4064)
			(end 0.7874 -0.4064)
			(stroke
				(width 0.1524)
				(type default)
			)
			(layer "B.SilkS")
		)
		(fp_line
			(start 0.7874 -0.4064)
			(end -0.7874 -0.4064)
			(stroke
				(width 0.1524)
				(type default)
			)
			(layer "B.SilkS")
		)
		(fp_line
			(start -0.7874 0.4064)
			(end 0.7874 0.4064)
			(stroke
				(width 0.1524)
				(type default)
			)
			(layer "B.SilkS")
		)
		(fp_line
			(start -0.7874 -0.4064)
			(end -0.7874 0.4064)
			(stroke
				(width 0.1524)
				(type default)
			)
			(layer "B.SilkS")
		)
		(fp_line
			(start 0.67945 0.3048)
			(end 0.67945 -0.305054)
			(stroke
				(width 0.1)
				(type default)
			)
			(layer "B.Fab")
		)
		(fp_line
			(start 0.67945 -0.305054)
			(end 0.12065 -0.305054)
			(stroke
				(width 0.1)
				(type default)
			)
			(layer "B.Fab")
		)
		(fp_line
			(start 0.12065 0.3048)
			(end 0.67945 0.3048)
			(stroke
				(width 0.1)
				(type default)
			)
			(layer "B.Fab")
		)
		(fp_line
			(start 0.12065 0.2794)
			(end 0.12065 0.3048)
			(stroke
				(width 0.1)
				(type default)
			)
			(layer "B.Fab")
		)
		(fp_line
			(start 0.12065 -0.2794)
			(end -0.12065 -0.2794)
			(stroke
				(width 0.1)
				(type default)
			)
			(layer "B.Fab")
		)
		(fp_line
			(start 0.12065 -0.305054)
			(end 0.12065 -0.2794)
			(stroke
				(width 0.1)
				(type default)
			)
			(layer "B.Fab")
		)
		(fp_line
			(start -0.120396 0.3048)
			(end -0.120396 0.2794)
			(stroke
				(width 0.1)
				(type default)
			)
			(layer "B.Fab")
		)
		(fp_line
			(start -0.120396 0.2794)
			(end 0.12065 0.2794)
			(stroke
				(width 0.1)
				(type default)
			)
			(layer "B.Fab")
		)
		(fp_line
			(start -0.12065 -0.2794)
			(end -0.12065 -0.3048)
			(stroke
				(width 0.1)
				(type default)
			)
			(layer "B.Fab")
		)
		(fp_line
			(start -0.12065 -0.3048)
			(end -0.67945 -0.3048)
			(stroke
				(width 0.1)
				(type default)
			)
			(layer "B.Fab")
		)
		(fp_line
			(start -0.67945 0.3048)
			(end -0.120396 0.3048)
			(stroke
				(width 0.1)
				(type default)
			)
			(layer "B.Fab")
		)
		(fp_line
			(start -0.67945 -0.3048)
			(end -0.67945 0.3048)
			(stroke
				(width 0.1)
				(type default)
			)
			(layer "B.Fab")
		)
		(pad "1" smd circle
			(at 0.40005 0)
			(size 0 0)
			(layers "B.Cu" "B.Mask" "B.Paste")
			(net "I3C_SPD_DDRABCD_CPU0_LVC1_SCL_7")
		)
		(pad "2" smd circle
			(at -0.40005 0)
			(size 0 0)
			(layers "B.Cu" "B.Mask" "B.Paste")
			(net "I3C_SPD_DDRABCD_CPU0_LVC1_SCL")
		)
	)
)
